# S9S_MB_2U (Grand Teton) — schematic netlist excerpt (pin names and nets, part order shuffled) for the footprints in the layout excerpt that follows; sources: Cadence DE-HDL packaged netlist, KiCad conversion of 03242023_DA0F0TMBIJ0_F0T_Motherboard_J_brd_V01_OCP.brd

PC478  Q_CAP  1UF 16V 10% X6S  pkg C0402  page 292 : A = PVCCINFAON_CPU1_VCC ; B = GND
C1770  Q_CAP  0.1UF 25V 10% X7R  pkg 0402  page 151 : A = P3V3_AUX ; B = GND

(kicad_pcb
	(version 20260206)
	(generator "pcbnew")
	(generator_version "10.0")
	(general
		(thickness 1.6)
		(legacy_teardrops no)
	)
	(paper "A4")
	(title_block
		(title "03242023_DA0F0TMBIJ0_F0T_Motherboard_J_brd_V01_OCP.brd")
		(comment 1 "Grand Teton / footprints 2402-2403 of 6105")
	)
	(layers
		(0 "F.Cu" signal "TOP")
		(4 "In1.Cu" signal "GND")
		(6 "In2.Cu" signal "IN1")
		(8 "In3.Cu" signal "GND1")
		(10 "In4.Cu" signal "IN2")
		(12 "In5.Cu" signal "GND2")
		(14 "In6.Cu" signal "IN3")
		(16 "In7.Cu" signal "GND3")
		(18 "In8.Cu" signal "VCC")
		(20 "In9.Cu" signal "VCC1")
		(22 "In10.Cu" signal "GND4")
		(24 "In11.Cu" signal "IN4")
		(26 "In12.Cu" signal "GND5")
		(28 "In13.Cu" signal "IN5")
		(30 "In14.Cu" signal "GND6")
		(32 "In15.Cu" signal "IN6")
		(34 "In16.Cu" signal "GND7")
		(2 "B.Cu" signal "BOTTOM")
		(9 "F.Adhes" user "F.Adhesive")
		(11 "B.Adhes" user "B.Adhesive")
		(13 "F.Paste" user "Package Geometry/Pastemask Top")
		(15 "B.Paste" user "Package Geometry/Pastemask Bottom")
		(5 "F.SilkS" user "Ref Des/Silkscreen Top")
		(7 "B.SilkS" user "Ref Des/Silkscreen Bottom")
		(1 "F.Mask" user "Board Geometry/Soldermask Top")
		(3 "B.Mask" user "Board Geometry/Soldermask Bottom")
		(17 "Dwgs.User" user "User.Drawings")
		(19 "Cmts.User" user "User.Comments")
		(21 "Eco1.User" user "User.Eco1")
		(23 "Eco2.User" user "User.Eco2")
		(25 "Edge.Cuts" user "Board Geometry/Outline")
		(27 "Margin" user)
		(31 "F.CrtYd" user "Package Geometry/Place Bound Top")
		(29 "B.CrtYd" user "Package Geometry/Place Bound Bottom")
		(35 "F.Fab" user "Ref Des/Assembly Top")
		(33 "B.Fab" user "Ref Des/Assembly Bottom")
	)
	(footprint ""
		(layer "F.Cu")
		(at 27.0383 -127.348996 180)
		(property "Reference" "PC478"
			(at 0 0 180)
			(layer "F.SilkS")
			(hide yes)
			(effects
				(font
					(size 1.27 1.27)
				)
			)
		)
		(property "Value" ""
			(at 0 0 180)
			(layer "F.Fab")
			(effects
				(font
					(size 1.27 1.27)
				)
			)
		)
		(duplicate_pad_numbers_are_jumpers no)
		(fp_line
			(start 0.7874 0.4064)
			(end -0.7874 0.4064)
			(stroke
				(width 0.1524)
				(type default)
			)
			(layer "F.SilkS")
		)
		(fp_line
			(start 0.7874 -0.4064)
			(end 0.7874 0.4064)
			(stroke
				(width 0.1524)
				(type default)
			)
			(layer "F.SilkS")
		)
		(fp_line
			(start -0.7874 0.4064)
			(end -0.7874 -0.4064)
			(stroke
				(width 0.1524)
				(type default)
			)
			(layer "F.SilkS")
		)
		(fp_line
			(start -0.7874 -0.4064)
			(end 0.7874 -0.4064)
			(stroke
				(width 0.1524)
				(type default)
			)
			(layer "F.SilkS")
		)
		(fp_line
			(start 0.67945 0.3048)
			(end 0.120396 0.3048)
			(stroke
				(width 0.1)
				(type default)
			)
			(layer "F.Fab")
		)
		(fp_line
			(start 0.67945 -0.3048)
			(end 0.67945 0.3048)
			(stroke
				(width 0.1)
				(type default)
			)
			(layer "F.Fab")
		)
		(fp_line
			(start 0.12065 -0.2794)
			(end 0.12065 -0.3048)
			(stroke
				(width 0.1)
				(type default)
			)
			(layer "F.Fab")
		)
		(fp_line
			(start 0.12065 -0.3048)
			(end 0.67945 -0.3048)
			(stroke
				(width 0.1)
				(type default)
			)
			(layer "F.Fab")
		)
		(fp_line
			(start 0.120396 0.3048)
			(end 0.120396 0.2794)
			(stroke
				(width 0.1)
				(type default)
			)
			(layer "F.Fab")
		)
		(fp_line
			(start 0.120396 0.2794)
			(end -0.12065 0.2794)
			(stroke
				(width 0.1)
				(type default)
			)
			(layer "F.Fab")
		)
		(fp_line
			(start -0.12065 0.3048)
			(end -0.67945 0.3048)
			(stroke
				(width 0.1)
				(type default)
			)
			(layer "F.Fab")
		)
		(fp_line
			(start -0.12065 0.2794)
			(end -0.12065 0.3048)
			(stroke
				(width 0.1)
				(type default)
			)
			(layer "F.Fab")
		)
		(fp_line
			(start -0.12065 -0.2794)
			(end 0.12065 -0.2794)
			(stroke
				(width 0.1)
				(type default)
			)
			(layer "F.Fab")
		)
		(fp_line
			(start -0.12065 -0.305054)
			(end -0.12065 -0.2794)
			(stroke
				(width 0.1)
				(type default)
			)
			(layer "F.Fab")
		)
		(fp_line
			(start -0.67945 0.3048)
			(end -0.67945 -0.305054)
			(stroke
				(width 0.1)
				(type default)
			)
			(layer "F.Fab")
		)
		(fp_line
			(start -0.67945 -0.305054)
			(end -0.12065 -0.305054)
			(stroke
				(width 0.1)
				(type default)
			)
			(layer "F.Fab")
		)
		(pad "1" smd circle
			(at -0.40005 0 180)
			(size 0 0)
			(layers "F.Cu" "F.Mask" "F.Paste")
			(net "PVCCINFAON_CPU1_VCC")
		)
		(pad "2" smd circle
			(at 0.40005 0 180)
			(size 0 0)
			(layers "F.Cu" "F.Mask" "F.Paste")
			(net "GND")
		)
	)
	(footprint ""
		(layer "F.Cu")
		(at 118.09222 -419.920928 90)
		(property "Reference" "C1770"
			(at 0 0 90)
			(layer "F.SilkS")
			(hide yes)
			(effects
				(font
					(size 1.27 1.27)
				)
			)
		)
		(property "Value" ""
			(at 0 0 90)
			(layer "F.Fab")
			(effects
				(font
					(size 1.27 1.27)
				)
			)
		)
		(duplicate_pad_numbers_are_jumpers no)
		(fp_line
			(start 0.7874 -0.4064)
			(end 0.7874 0.4064)
			(stroke
				(width 0.1524)
				(type default)
			)
			(layer "F.SilkS")
		)
		(fp_line
			(start -0.7874 -0.4064)
			(end 0.7874 -0.4064)
			(stroke
				(width 0.1524)
				(type default)
			)
			(layer "F.SilkS")
		)
		(fp_line
			(start 0.7874 0.4064)
			(end -0.7874 0.4064)
			(stroke
				(width 0.1524)
				(type default)
			)
			(layer "F.SilkS")
		)
		(fp_line
			(start -0.7874 0.4064)
			(end -0.7874 -0.4064)
			(stroke
				(width 0.1524)
				(type default)
			)
			(layer "F.SilkS")
		)
		(fp_line
			(start -0.12065 -0.305054)
			(end -0.12065 -0.2794)
			(stroke
				(width 0.1)
				(type default)
			)
			(layer "F.Fab")
		)
		(fp_line
			(start -0.67945 -0.305054)
			(end -0.12065 -0.305054)
			(stroke
				(width 0.1)
				(type default)
			)
			(layer "F.Fab")
		)
		(fp_line
			(start 0.67945 -0.3048)
			(end 0.67945 0.3048)
			(stroke
				(width 0.1)
				(type default)
			)
			(layer "F.Fab")
		)
		(fp_line
			(start 0.12065 -0.3048)
			(end 0.67945 -0.3048)
			(stroke
				(width 0.1)
				(type default)
			)
			(layer "F.Fab")
		)
		(fp_line
			(start 0.12065 -0.2794)
			(end 0.12065 -0.3048)
			(stroke
				(width 0.1)
				(type default)
			)
			(layer "F.Fab")
		)
		(fp_line
			(start -0.12065 -0.2794)
			(end 0.12065 -0.2794)
			(stroke
				(width 0.1)
				(type default)
			)
			(layer "F.Fab")
		)
		(fp_line
			(start 0.120396 0.2794)
			(end -0.12065 0.2794)
			(stroke
				(width 0.1)
				(type default)
			)
			(layer "F.Fab")
		)
		(fp_line
			(start -0.12065 0.2794)
			(end -0.12065 0.3048)
			(stroke
				(width 0.1)
				(type default)
			)
			(layer "F.Fab")
		)
		(fp_line
			(start 0.67945 0.3048)
			(end 0.120396 0.3048)
			(stroke
				(width 0.1)
				(type default)
			)
			(layer "F.Fab")
		)
		(fp_line
			(start 0.120396 0.3048)
			(end 0.120396 0.2794)
			(stroke
				(width 0.1)
				(type default)
			)
			(layer "F.Fab")
		)
		(fp_line
			(start -0.12065 0.3048)
			(end -0.67945 0.3048)
			(stroke
				(width 0.1)
				(type default)
			)
			(layer "F.Fab")
		)
		(fp_line
			(start -0.67945 0.3048)
			(end -0.67945 -0.305054)
			(stroke
				(width 0.1)
				(type default)
			)
			(layer "F.Fab")
		)
		(pad "1" smd circle
			(at -0.40005 0 90)
			(size 0 0)
			(layers "F.Cu" "F.Mask" "F.Paste")
			(net "P3V3_AUX")
		)
		(pad "2" smd circle
			(at 0.40005 0 90)
			(size 0 0)
			(layers "F.Cu" "F.Mask" "F.Paste")
			(net "GND")
		)
	)
)
